# S9S_MB_2U (Grand Teton) — schematic netlist excerpt (pin names and nets, part order shuffled) for the footprints in the layout excerpt that follows; sources: Cadence DE-HDL packaged netlist, KiCad conversion of 03242023_DA0F0TMBIJ0_F0T_Motherboard_J_brd_V01_OCP.brd

C1016  Q_CAP  22UF 4V 20% X6S  pkg C0402  page 74 : A = PVCCIN_CPU0 ; B = GND
PC1196_P1_4  Q_CAP  1UF 16V 10% X6S  pkg C0402  page 290 : A = SW_P12V_PVCCFA_EHV_FIVRA_CPU1_L ; B = GND
C681  Q_CAP_DIFFBUS  DIFF BUS_0.22UF 6.3V 20% X6S  pkg C0201  page 177 : \1\ = P5E_CPU1_PE4_TX_C_DP<14> ; \2\ = P5E_CPU1_PE4_TX_DP<14>

(kicad_pcb
	(version 20260206)
	(generator "pcbnew")
	(generator_version "10.0")
	(general
		(thickness 1.6)
		(legacy_teardrops no)
	)
	(paper "A4")
	(title_block
		(title "03242023_DA0F0TMBIJ0_F0T_Motherboard_J_brd_V01_OCP.brd")
		(comment 1 "Grand Teton / footprints 3634-3636 of 6105")
	)
	(layers
		(0 "F.Cu" signal "TOP")
		(4 "In1.Cu" signal "GND")
		(6 "In2.Cu" signal "IN1")
		(8 "In3.Cu" signal "GND1")
		(10 "In4.Cu" signal "IN2")
		(12 "In5.Cu" signal "GND2")
		(14 "In6.Cu" signal "IN3")
		(16 "In7.Cu" signal "GND3")
		(18 "In8.Cu" signal "VCC")
		(20 "In9.Cu" signal "VCC1")
		(22 "In10.Cu" signal "GND4")
		(24 "In11.Cu" signal "IN4")
		(26 "In12.Cu" signal "GND5")
		(28 "In13.Cu" signal "IN5")
		(30 "In14.Cu" signal "GND6")
		(32 "In15.Cu" signal "IN6")
		(34 "In16.Cu" signal "GND7")
		(2 "B.Cu" signal "BOTTOM")
		(9 "F.Adhes" user "F.Adhesive")
		(11 "B.Adhes" user "B.Adhesive")
		(13 "F.Paste" user "Package Geometry/Pastemask Top")
		(15 "B.Paste" user "Package Geometry/Pastemask Bottom")
		(5 "F.SilkS" user "Ref Des/Silkscreen Top")
		(7 "B.SilkS" user "Ref Des/Silkscreen Bottom")
		(1 "F.Mask" user "Board Geometry/Soldermask Top")
		(3 "B.Mask" user "Board Geometry/Soldermask Bottom")
		(17 "Dwgs.User" user "User.Drawings")
		(19 "Cmts.User" user "User.Comments")
		(21 "Eco1.User" user "User.Eco1")
		(23 "Eco2.User" user "User.Eco2")
		(25 "Edge.Cuts" user "Board Geometry/Outline")
		(27 "Margin" user)
		(31 "F.CrtYd" user "Package Geometry/Place Bound Top")
		(29 "B.CrtYd" user "Package Geometry/Place Bound Bottom")
		(35 "F.Fab" user "Ref Des/Assembly Top")
		(33 "B.Fab" user "Ref Des/Assembly Bottom")
	)
	(footprint ""
		(layer "F.Cu")
		(at 93.100398 -408.517344 -90)
		(property "Reference" "C681"
			(at 0 0 270)
			(layer "F.SilkS")
			(hide yes)
			(effects
				(font
					(size 1.27 1.27)
				)
			)
		)
		(property "Value" ""
			(at 0 0 270)
			(layer "F.Fab")
			(effects
				(font
					(size 1.27 1.27)
				)
			)
		)
		(duplicate_pad_numbers_are_jumpers no)
		(fp_line
			(start -0.299974 0.150114)
			(end -0.299974 -0.150114)
			(stroke
				(width 0.1)
				(type default)
			)
			(layer "F.Fab")
		)
		(fp_line
			(start 0.299974 0.150114)
			(end -0.299974 0.150114)
			(stroke
				(width 0.1)
				(type default)
			)
			(layer "F.Fab")
		)
		(fp_line
			(start -0.299974 -0.150114)
			(end 0.299974 -0.150114)
			(stroke
				(width 0.1)
				(type default)
			)
			(layer "F.Fab")
		)
		(fp_line
			(start 0.299974 -0.150114)
			(end 0.299974 0.150114)
			(stroke
				(width 0.1)
				(type default)
			)
			(layer "F.Fab")
		)
		(pad "1" smd rect
			(at -0.2667 0 270)
			(size 0.3048 0.381)
			(layers "F.Cu" "F.Mask" "F.Paste")
			(net "P5E_CPU1_PE4_TX_C_DP<14>")
		)
		(pad "2" smd rect
			(at 0.2667 0 270)
			(size 0.3048 0.381)
			(layers "F.Cu" "F.Mask" "F.Paste")
			(net "P5E_CPU1_PE4_TX_DP<14>")
		)
	)
	(footprint ""
		(layer "F.Cu")
		(at 364.50143 -252.956314 -90)
		(property "Reference" "C1016"
			(at 0 0 270)
			(layer "F.SilkS")
			(hide yes)
			(effects
				(font
					(size 1.27 1.27)
				)
			)
		)
		(property "Value" ""
			(at 0 0 270)
			(layer "F.Fab")
			(effects
				(font
					(size 1.27 1.27)
				)
			)
		)
		(duplicate_pad_numbers_are_jumpers no)
		(fp_line
			(start -0.7874 0.4064)
			(end -0.7874 -0.4064)
			(stroke
				(width 0.1524)
				(type default)
			)
			(layer "F.SilkS")
		)
		(fp_line
			(start 0.7874 0.4064)
			(end -0.7874 0.4064)
			(stroke
				(width 0.1524)
				(type default)
			)
			(layer "F.SilkS")
		)
		(fp_line
			(start -0.7874 -0.4064)
			(end 0.7874 -0.4064)
			(stroke
				(width 0.1524)
				(type default)
			)
			(layer "F.SilkS")
		)
		(fp_line
			(start 0.7874 -0.4064)
			(end 0.7874 0.4064)
			(stroke
				(width 0.1524)
				(type default)
			)
			(layer "F.SilkS")
		)
		(fp_line
			(start -0.67945 0.3048)
			(end -0.67945 -0.305054)
			(stroke
				(width 0.1)
				(type default)
			)
			(layer "F.Fab")
		)
		(fp_line
			(start -0.12065 0.3048)
			(end -0.67945 0.3048)
			(stroke
				(width 0.1)
				(type default)
			)
			(layer "F.Fab")
		)
		(fp_line
			(start 0.120396 0.3048)
			(end 0.120396 0.2794)
			(stroke
				(width 0.1)
				(type default)
			)
			(layer "F.Fab")
		)
		(fp_line
			(start 0.67945 0.3048)
			(end 0.120396 0.3048)
			(stroke
				(width 0.1)
				(type default)
			)
			(layer "F.Fab")
		)
		(fp_line
			(start -0.12065 0.2794)
			(end -0.12065 0.3048)
			(stroke
				(width 0.1)
				(type default)
			)
			(layer "F.Fab")
		)
		(fp_line
			(start 0.120396 0.2794)
			(end -0.12065 0.2794)
			(stroke
				(width 0.1)
				(type default)
			)
			(layer "F.Fab")
		)
		(fp_line
			(start -0.12065 -0.2794)
			(end 0.12065 -0.2794)
			(stroke
				(width 0.1)
				(type default)
			)
			(layer "F.Fab")
		)
		(fp_line
			(start 0.12065 -0.2794)
			(end 0.12065 -0.3048)
			(stroke
				(width 0.1)
				(type default)
			)
			(layer "F.Fab")
		)
		(fp_line
			(start 0.12065 -0.3048)
			(end 0.67945 -0.3048)
			(stroke
				(width 0.1)
				(type default)
			)
			(layer "F.Fab")
		)
		(fp_line
			(start 0.67945 -0.3048)
			(end 0.67945 0.3048)
			(stroke
				(width 0.1)
				(type default)
			)
			(layer "F.Fab")
		)
		(fp_line
			(start -0.67945 -0.305054)
			(end -0.12065 -0.305054)
			(stroke
				(width 0.1)
				(type default)
			)
			(layer "F.Fab")
		)
		(fp_line
			(start -0.12065 -0.305054)
			(end -0.12065 -0.2794)
			(stroke
				(width 0.1)
				(type default)
			)
			(layer "F.Fab")
		)
		(pad "1" smd circle
			(at -0.40005 0 270)
			(size 0 0)
			(layers "F.Cu" "F.Mask" "F.Paste")
			(net "PVCCIN_CPU0")
		)
		(pad "2" smd circle
			(at 0.40005 0 270)
			(size 0 0)
			(layers "F.Cu" "F.Mask" "F.Paste")
			(net "GND")
		)
	)
	(footprint ""
		(layer "F.Cu")
		(at 45.136308 -353.61626 -90)
		(property "Reference" "PC1196_P1_4"
			(at 0 0 270)
			(layer "F.SilkS")
			(hide yes)
			(effects
				(font
					(size 1.27 1.27)
				)
			)
		)
		(property "Value" ""
			(at 0 0 270)
			(layer "F.Fab")
			(effects
				(font
					(size 1.27 1.27)
				)
			)
		)
		(duplicate_pad_numbers_are_jumpers no)
		(fp_line
			(start -0.7874 0.4064)
			(end -0.7874 -0.4064)
			(stroke
				(width 0.1524)
				(type default)
			)
			(layer "F.SilkS")
		)
		(fp_line
			(start 0.7874 0.4064)
			(end -0.7874 0.4064)
			(stroke
				(width 0.1524)
				(type default)
			)
			(layer "F.SilkS")
		)
		(fp_line
			(start -0.7874 -0.4064)
			(end 0.7874 -0.4064)
			(stroke
				(width 0.1524)
				(type default)
			)
			(layer "F.SilkS")
		)
		(fp_line
			(start 0.7874 -0.4064)
			(end 0.7874 0.4064)
			(stroke
				(width 0.1524)
				(type default)
			)
			(layer "F.SilkS")
		)
		(fp_line
			(start -0.67945 0.3048)
			(end -0.67945 -0.305054)
			(stroke
				(width 0.1)
				(type default)
			)
			(layer "F.Fab")
		)
		(fp_line
			(start -0.12065 0.3048)
			(end -0.67945 0.3048)
			(stroke
				(width 0.1)
				(type default)
			)
			(layer "F.Fab")
		)
		(fp_line
			(start 0.120396 0.3048)
			(end 0.120396 0.2794)
			(stroke
				(width 0.1)
				(type default)
			)
			(layer "F.Fab")
		)
		(fp_line
			(start 0.67945 0.3048)
			(end 0.120396 0.3048)
			(stroke
				(width 0.1)
				(type default)
			)
			(layer "F.Fab")
		)
		(fp_line
			(start -0.12065 0.2794)
			(end -0.12065 0.3048)
			(stroke
				(width 0.1)
				(type default)
			)
			(layer "F.Fab")
		)
		(fp_line
			(start 0.120396 0.2794)
			(end -0.12065 0.2794)
			(stroke
				(width 0.1)
				(type default)
			)
			(layer "F.Fab")
		)
		(fp_line
			(start -0.12065 -0.2794)
			(end 0.12065 -0.2794)
			(stroke
				(width 0.1)
				(type default)
			)
			(layer "F.Fab")
		)
		(fp_line
			(start 0.12065 -0.2794)
			(end 0.12065 -0.3048)
			(stroke
				(width 0.1)
				(type default)
			)
			(layer "F.Fab")
		)
		(fp_line
			(start 0.12065 -0.3048)
			(end 0.67945 -0.3048)
			(stroke
				(width 0.1)
				(type default)
			)
			(layer "F.Fab")
		)
		(fp_line
			(start 0.67945 -0.3048)
			(end 0.67945 0.3048)
			(stroke
				(width 0.1)
				(type default)
			)
			(layer "F.Fab")
		)
		(fp_line
			(start -0.67945 -0.305054)
			(end -0.12065 -0.305054)
			(stroke
				(width 0.1)
				(type default)
			)
			(layer "F.Fab")
		)
		(fp_line
			(start -0.12065 -0.305054)
			(end -0.12065 -0.2794)
			(stroke
				(width 0.1)
				(type default)
			)
			(layer "F.Fab")
		)
		(pad "1" smd circle
			(at -0.40005 0 270)
			(size 0 0)
			(layers "F.Cu" "F.Mask" "F.Paste")
			(net "SW_P12V_PVCCFA_EHV_FIVRA_CPU1_L")
		)
		(pad "2" smd circle
			(at 0.40005 0 270)
			(size 0 0)
			(layers "F.Cu" "F.Mask" "F.Paste")
			(net "GND")
		)
	)
)
